(kicad_pcb
	(version 20260206)
	(generator "pcbnew")
	(generator_version "10.0")
	(general
		(thickness 1.6)
		(legacy_teardrops no)
	)
	(paper "A4")
	(title_block
		(title "15969-1a.1015WZS0858.brd")
		(comment 1 "Tioga Pass / footprints 269-275 of 295")
	)
	(layers
		(0 "F.Cu" signal "TOP")
		(4 "In1.Cu" signal "L2GND")
		(6 "In2.Cu" signal "L3")
		(8 "In3.Cu" signal "L4")
		(10 "In4.Cu" signal "L5GND")
		(2 "B.Cu" signal "BOTTOM")
		(9 "F.Adhes" user "F.Adhesive")
		(11 "B.Adhes" user "B.Adhesive")
		(13 "F.Paste" user "Package Geometry/Pastemask Top")
		(15 "B.Paste" user "Package Geometry/Pastemask Bottom")
		(5 "F.SilkS" user "Ref Des/Silkscreen Top")
		(7 "B.SilkS" user "Ref Des/Silkscreen Bottom")
		(1 "F.Mask" user "Board Geometry/Soldermask Top")
		(3 "B.Mask" user "Board Geometry/Soldermask Bottom")
		(17 "Dwgs.User" user "User.Drawings")
		(19 "Cmts.User" user "User.Comments")
		(21 "Eco1.User" user "User.Eco1")
		(23 "Eco2.User" user "User.Eco2")
		(25 "Edge.Cuts" user "Board Geometry/Outline")
		(27 "Margin" user)
		(31 "F.CrtYd" user "Package Geometry/Place Bound Top")
		(29 "B.CrtYd" user "Package Geometry/Place Bound Bottom")
		(35 "F.Fab" user "Ref Des/Assembly Top")
		(33 "B.Fab" user "Ref Des/Assembly Bottom")
	)
	(footprint ""
		(layer "B.Cu")
		(at 16.2814 -11.4808 -90)
		(property "Reference" "PR4"
			(at 0 0 90)
			(layer "B.SilkS")
			(hide yes)
			(effects
				(font
					(size 1.27 1.27)
				)
				(justify mirror)
			)
		)
		(property "Value" "10KR2F-2-GP"
			(at -0.064008 -3.993896 270)
			(unlocked yes)
			(layer "B.Fab")
			(hide yes)
			(effects
				(font
					(size 1.016 1.016)
					(thickness 0.1524)
				)
				(justify mirror)
			)
		)
		(property "Device Type" "R402H16"
			(at -0.064008 -5.517896 270)
			(unlocked yes)
			(layer "B.Fab")
			(hide yes)
			(effects
				(font
					(size 1.016 1.016)
					(thickness 0.1524)
				)
				(justify mirror)
			)
		)
		(duplicate_pad_numbers_are_jumpers no)
		(fp_line
			(start -0.508 -0.9398)
			(end 0.508 -0.9398)
			(stroke
				(width 0.1524)
				(type default)
			)
			(layer "B.SilkS")
		)
		(fp_line
			(start 0.508 -0.9398)
			(end 0.508 0.9398)
			(stroke
				(width 0.1524)
				(type default)
			)
			(layer "B.SilkS")
		)
		(fp_rect
			(start 0.508 0.9398)
			(end -0.508 -0.9398)
			(stroke
				(width 0)
				(type default)
			)
			(fill no)
			(layer "B.CrtYd")
		)
		(fp_rect
			(start 0.508 0.9398)
			(end -0.508 -0.9398)
			(stroke
				(width 0)
				(type default)
			)
			(fill no)
			(layer "B.Fab")
		)
		(pad "1" smd custom
			(at 0 -0.4445 90)
			(size 0.1397 0.1397)
			(layers "B.Cu" "B.Mask" "B.Paste")
			(net "P3V3_FB")
			(options
				(clearance outline)
				(anchor circle)
			)
			(primitives
				(gr_poly
					(pts
						(arc
							(start -0.1778 0.2794)
							(mid -0.249642 0.249642)
							(end -0.2794 0.1778)
						)
						(arc
							(start -0.2794 -0.1778)
							(mid -0.249642 -0.249642)
							(end -0.1778 -0.2794)
						)
						(arc
							(start 0.1778 -0.2794)
							(mid 0.249642 -0.249642)
							(end 0.2794 -0.1778)
						)
						(arc
							(start 0.2794 0.1778)
							(mid 0.249642 0.249642)
							(end 0.1778 0.2794)
						)
					)
					(width 0)
					(fill yes)
				)
			)
		)
		(pad "2" smd custom
			(at 0 0.4445 90)
			(size 0.1397 0.1397)
			(layers "B.Cu" "B.Mask" "B.Paste")
			(net "P3V3_VFB_R")
			(options
				(clearance outline)
				(anchor circle)
			)
			(primitives
				(gr_poly
					(pts
						(arc
							(start -0.1778 0.2794)
							(mid -0.249642 0.249642)
							(end -0.2794 0.1778)
						)
						(arc
							(start -0.2794 -0.1778)
							(mid -0.249642 -0.249642)
							(end -0.1778 -0.2794)
						)
						(arc
							(start 0.1778 -0.2794)
							(mid 0.249642 -0.249642)
							(end 0.2794 -0.1778)
						)
						(arc
							(start 0.2794 0.1778)
							(mid 0.249642 0.249642)
							(end 0.1778 0.2794)
						)
					)
					(width 0)
					(fill yes)
				)
			)
		)
	)
	(footprint ""
		(layer "B.Cu")
		(at 129.0066 -32.512)
		(property "Reference" "LU2"
			(at 0 0 0)
			(layer "B.SilkS")
			(hide yes)
			(effects
				(font
					(size 1.27 1.27)
				)
				(justify mirror)
			)
		)
		(property "Value" "MMZ1608S301AT-GP"
			(at 0.0254 -2.8956 0)
			(unlocked yes)
			(layer "B.Fab")
			(hide yes)
			(effects
				(font
					(size 1.016 1.016)
					(thickness 0.1524)
				)
				(justify mirror)
			)
		)
		(property "Device Type" "L1608-UH38"
			(at 0.0254 -4.4196 0)
			(unlocked yes)
			(layer "B.Fab")
			(hide yes)
			(effects
				(font
					(size 1.016 1.016)
					(thickness 0.1524)
				)
				(justify mirror)
			)
		)
		(duplicate_pad_numbers_are_jumpers no)
		(fp_line
			(start -0.254 0)
			(end 0.254 0)
			(stroke
				(width 0.2032)
				(type default)
			)
			(layer "B.SilkS")
		)
		(fp_rect
			(start 0.5842 1.3335)
			(end -0.5842 -1.3335)
			(stroke
				(width 0)
				(type default)
			)
			(fill no)
			(layer "B.CrtYd")
		)
		(fp_rect
			(start 0.5842 1.3335)
			(end -0.5842 -1.3335)
			(stroke
				(width 0)
				(type default)
			)
			(fill no)
			(layer "B.Fab")
		)
		(pad "1" smd custom
			(at 0 -0.762 180)
			(size 0.2159 0.2159)
			(layers "B.Cu" "B.Mask" "B.Paste")
			(net "P3V3")
			(options
				(clearance outline)
				(anchor circle)
			)
			(primitives
				(gr_poly
					(pts
						(arc
							(start -0.3302 0.4318)
							(mid -0.402042 0.402042)
							(end -0.4318 0.3302)
						)
						(arc
							(start -0.4318 -0.3302)
							(mid -0.402042 -0.402042)
							(end -0.3302 -0.4318)
						)
						(arc
							(start 0.3302 -0.4318)
							(mid 0.402042 -0.402042)
							(end 0.4318 -0.3302)
						)
						(arc
							(start 0.4318 0.3302)
							(mid 0.402042 0.402042)
							(end 0.3302 0.4318)
						)
					)
					(width 0)
					(fill yes)
				)
			)
		)
		(pad "2" smd custom
			(at 0 0.762 180)
			(size 0.2159 0.2159)
			(layers "B.Cu" "B.Mask" "B.Paste")
			(net "P3V3_USB_HUB")
			(options
				(clearance outline)
				(anchor circle)
			)
			(primitives
				(gr_poly
					(pts
						(arc
							(start -0.3302 0.4318)
							(mid -0.402042 0.402042)
							(end -0.4318 0.3302)
						)
						(arc
							(start -0.4318 -0.3302)
							(mid -0.402042 -0.402042)
							(end -0.3302 -0.4318)
						)
						(arc
							(start 0.3302 -0.4318)
							(mid 0.402042 -0.402042)
							(end 0.4318 -0.3302)
						)
						(arc
							(start 0.4318 0.3302)
							(mid 0.402042 0.402042)
							(end 0.3302 0.4318)
						)
					)
					(width 0)
					(fill yes)
				)
			)
		)
	)
	(footprint ""
		(layer "B.Cu")
		(at 25.2984 -23.6728 180)
		(property "Reference" "R150"
			(at 0 0 0)
			(layer "B.SilkS")
			(hide yes)
			(effects
				(font
					(size 1.27 1.27)
				)
				(justify mirror)
			)
		)
		(property "Value" "10KR2F-2-GP"
			(at -0.064008 -3.993896 180)
			(unlocked yes)
			(layer "B.Fab")
			(hide yes)
			(effects
				(font
					(size 1.016 1.016)
					(thickness 0.1524)
				)
				(justify mirror)
			)
		)
		(property "Device Type" "R402H16"
			(at -0.064008 -5.517896 180)
			(unlocked yes)
			(layer "B.Fab")
			(hide yes)
			(effects
				(font
					(size 1.016 1.016)
					(thickness 0.1524)
				)
				(justify mirror)
			)
		)
		(duplicate_pad_numbers_are_jumpers no)
		(fp_line
			(start 0.508 -0.9398)
			(end 0.508 0.9398)
			(stroke
				(width 0.1524)
				(type default)
			)
			(layer "B.SilkS")
		)
		(fp_line
			(start -0.508 -0.9398)
			(end 0.508 -0.9398)
			(stroke
				(width 0.1524)
				(type default)
			)
			(layer "B.SilkS")
		)
		(fp_rect
			(start 0.508 0.9398)
			(end -0.508 -0.9398)
			(stroke
				(width 0)
				(type default)
			)
			(fill no)
			(layer "B.CrtYd")
		)
		(fp_rect
			(start 0.508 0.9398)
			(end -0.508 -0.9398)
			(stroke
				(width 0)
				(type default)
			)
			(fill no)
			(layer "B.Fab")
		)
		(pad "1" smd custom
			(at 0 -0.4445)
			(size 0.1397 0.1397)
			(layers "B.Cu" "B.Mask" "B.Paste")
			(net "ATX_VMONITOR_A0")
			(options
				(clearance outline)
				(anchor circle)
			)
			(primitives
				(gr_poly
					(pts
						(arc
							(start -0.1778 0.2794)
							(mid -0.249642 0.249642)
							(end -0.2794 0.1778)
						)
						(arc
							(start -0.2794 -0.1778)
							(mid -0.249642 -0.249642)
							(end -0.1778 -0.2794)
						)
						(arc
							(start 0.1778 -0.2794)
							(mid 0.249642 -0.249642)
							(end 0.2794 -0.1778)
						)
						(arc
							(start 0.2794 0.1778)
							(mid 0.249642 0.249642)
							(end 0.1778 0.2794)
						)
					)
					(width 0)
					(fill yes)
				)
			)
		)
		(pad "2" smd custom
			(at 0 0.4445)
			(size 0.1397 0.1397)
			(layers "B.Cu" "B.Mask" "B.Paste")
			(net "GND")
			(options
				(clearance outline)
				(anchor circle)
			)
			(primitives
				(gr_poly
					(pts
						(arc
							(start -0.1778 0.2794)
							(mid -0.249642 0.249642)
							(end -0.2794 0.1778)
						)
						(arc
							(start -0.2794 -0.1778)
							(mid -0.249642 -0.249642)
							(end -0.1778 -0.2794)
						)
						(arc
							(start 0.1778 -0.2794)
							(mid 0.249642 -0.249642)
							(end 0.2794 -0.1778)
						)
						(arc
							(start 0.2794 0.1778)
							(mid 0.249642 0.249642)
							(end 0.1778 0.2794)
						)
					)
					(width 0)
					(fill yes)
				)
			)
		)
	)
	(footprint ""
		(layer "B.Cu")
		(at 30.4165 2.1971)
		(property "Reference" "PC9"
			(at 0 0 0)
			(layer "B.SilkS")
			(hide yes)
			(effects
				(font
					(size 1.27 1.27)
				)
				(justify mirror)
			)
		)
		(property "Value" "SC22U6D3V5MX-5-GP"
			(at 0.0762 -6.1214 0)
			(unlocked yes)
			(layer "B.Fab")
			(hide yes)
			(effects
				(font
					(size 1.016 1.016)
					(thickness 0.1524)
				)
				(justify mirror)
			)
		)
		(property "Device Type" "C805H56"
			(at 0.0762 -8.1534 0)
			(unlocked yes)
			(layer "B.Fab")
			(hide yes)
			(effects
				(font
					(size 1.016 1.016)
					(thickness 0.1524)
				)
				(justify mirror)
			)
		)
		(duplicate_pad_numbers_are_jumpers no)
		(fp_line
			(start -0.635 0)
			(end 0.635 0)
			(stroke
				(width 0.508)
				(type default)
			)
			(layer "B.SilkS")
		)
		(fp_rect
			(start 0.9652 1.778)
			(end -0.9652 -1.778)
			(stroke
				(width 0)
				(type default)
			)
			(fill no)
			(layer "B.CrtYd")
		)
		(fp_poly
			(pts
				(xy 0.9652 -1.778) (xy -0.9652 -1.778) (xy -0.9652 1.778) (xy 0.9652 1.778)
			)
			(stroke
				(width 0)
				(type default)
			)
			(fill no)
			(layer "B.Fab")
		)
		(pad "1" smd rect
			(at 0 -0.9652 180)
			(size 1.397 1.143)
			(layers "B.Cu" "B.Mask" "B.Paste")
			(net "P3V3_VR")
		)
		(pad "2" smd rect
			(at 0 0.9652 180)
			(size 1.397 1.143)
			(layers "B.Cu" "B.Mask" "B.Paste")
			(net "GND")
		)
	)
	(footprint ""
		(layer "B.Cu")
		(at 122.8344 -8.8392 -90)
		(property "Reference" "R39"
			(at 0 0 90)
			(layer "B.SilkS")
			(hide yes)
			(effects
				(font
					(size 1.27 1.27)
				)
				(justify mirror)
			)
		)
		(property "Value" "10KR2F-2-GP"
			(at -0.064008 -3.993896 270)
			(unlocked yes)
			(layer "B.Fab")
			(hide yes)
			(effects
				(font
					(size 1.016 1.016)
					(thickness 0.1524)
				)
				(justify mirror)
			)
		)
		(property "Device Type" "R402H16"
			(at -0.064008 -5.517896 270)
			(unlocked yes)
			(layer "B.Fab")
			(hide yes)
			(effects
				(font
					(size 1.016 1.016)
					(thickness 0.1524)
				)
				(justify mirror)
			)
		)
		(duplicate_pad_numbers_are_jumpers no)
		(fp_line
			(start -0.508 -0.9398)
			(end 0.508 -0.9398)
			(stroke
				(width 0.1524)
				(type default)
			)
			(layer "B.SilkS")
		)
		(fp_line
			(start 0.508 -0.9398)
			(end 0.508 0.9398)
			(stroke
				(width 0.1524)
				(type default)
			)
			(layer "B.SilkS")
		)
		(fp_rect
			(start 0.508 0.9398)
			(end -0.508 -0.9398)
			(stroke
				(width 0)
				(type default)
			)
			(fill no)
			(layer "B.CrtYd")
		)
		(fp_rect
			(start 0.508 0.9398)
			(end -0.508 -0.9398)
			(stroke
				(width 0)
				(type default)
			)
			(fill no)
			(layer "B.Fab")
		)
		(pad "1" smd custom
			(at 0 -0.4445 90)
			(size 0.1397 0.1397)
			(layers "B.Cu" "B.Mask" "B.Paste")
			(net "SMB_P_HUB_A1")
			(options
				(clearance outline)
				(anchor circle)
			)
			(primitives
				(gr_poly
					(pts
						(arc
							(start -0.1778 0.2794)
							(mid -0.249642 0.249642)
							(end -0.2794 0.1778)
						)
						(arc
							(start -0.2794 -0.1778)
							(mid -0.249642 -0.249642)
							(end -0.1778 -0.2794)
						)
						(arc
							(start 0.1778 -0.2794)
							(mid 0.249642 -0.249642)
							(end 0.2794 -0.1778)
						)
						(arc
							(start 0.2794 0.1778)
							(mid 0.249642 0.249642)
							(end 0.1778 0.2794)
						)
					)
					(width 0)
					(fill yes)
				)
			)
		)
		(pad "2" smd custom
			(at 0 0.4445 90)
			(size 0.1397 0.1397)
			(layers "B.Cu" "B.Mask" "B.Paste")
			(net "GND")
			(options
				(clearance outline)
				(anchor circle)
			)
			(primitives
				(gr_poly
					(pts
						(arc
							(start -0.1778 0.2794)
							(mid -0.249642 0.249642)
							(end -0.2794 0.1778)
						)
						(arc
							(start -0.2794 -0.1778)
							(mid -0.249642 -0.249642)
							(end -0.1778 -0.2794)
						)
						(arc
							(start 0.1778 -0.2794)
							(mid 0.249642 -0.249642)
							(end 0.2794 -0.1778)
						)
						(arc
							(start 0.2794 0.1778)
							(mid 0.249642 0.249642)
							(end 0.1778 0.2794)
						)
					)
					(width 0)
					(fill yes)
				)
			)
		)
	)
	(footprint ""
		(layer "B.Cu")
		(at 117.4496 1.6256 180)
		(property "Reference" "R8"
			(at 0 0 0)
			(layer "B.SilkS")
			(hide yes)
			(effects
				(font
					(size 1.27 1.27)
				)
				(justify mirror)
			)
		)
		(property "Value" "4K7R2F-GP"
			(at -0.064008 -3.993896 180)
			(unlocked yes)
			(layer "B.Fab")
			(hide yes)
			(effects
				(font
					(size 1.016 1.016)
					(thickness 0.1524)
				)
				(justify mirror)
			)
		)
		(property "Device Type" "R402H16"
			(at -0.064008 -5.517896 180)
			(unlocked yes)
			(layer "B.Fab")
			(hide yes)
			(effects
				(font
					(size 1.016 1.016)
					(thickness 0.1524)
				)
				(justify mirror)
			)
		)
		(duplicate_pad_numbers_are_jumpers no)
		(fp_line
			(start 0.508 -0.9398)
			(end 0.508 0.9398)
			(stroke
				(width 0.1524)
				(type default)
			)
			(layer "B.SilkS")
		)
		(fp_line
			(start -0.508 -0.9398)
			(end 0.508 -0.9398)
			(stroke
				(width 0.1524)
				(type default)
			)
			(layer "B.SilkS")
		)
		(fp_rect
			(start 0.508 0.9398)
			(end -0.508 -0.9398)
			(stroke
				(width 0)
				(type default)
			)
			(fill no)
			(layer "B.CrtYd")
		)
		(fp_rect
			(start 0.508 0.9398)
			(end -0.508 -0.9398)
			(stroke
				(width 0)
				(type default)
			)
			(fill no)
			(layer "B.Fab")
		)
		(pad "1" smd custom
			(at 0 -0.4445)
			(size 0.1397 0.1397)
			(layers "B.Cu" "B.Mask" "B.Paste")
			(net "P3V3_STBY")
			(options
				(clearance outline)
				(anchor circle)
			)
			(primitives
				(gr_poly
					(pts
						(arc
							(start -0.1778 0.2794)
							(mid -0.249642 0.249642)
							(end -0.2794 0.1778)
						)
						(arc
							(start -0.2794 -0.1778)
							(mid -0.249642 -0.249642)
							(end -0.1778 -0.2794)
						)
						(arc
							(start 0.1778 -0.2794)
							(mid 0.249642 -0.249642)
							(end 0.2794 -0.1778)
						)
						(arc
							(start 0.2794 0.1778)
							(mid 0.249642 0.249642)
							(end 0.1778 0.2794)
						)
					)
					(width 0)
					(fill yes)
				)
			)
		)
		(pad "2" smd custom
			(at 0 0.4445)
			(size 0.1397 0.1397)
			(layers "B.Cu" "B.Mask" "B.Paste")
			(net "SMCLK_BMC_DEVICE")
			(options
				(clearance outline)
				(anchor circle)
			)
			(primitives
				(gr_poly
					(pts
						(arc
							(start -0.1778 0.2794)
							(mid -0.249642 0.249642)
							(end -0.2794 0.1778)
						)
						(arc
							(start -0.2794 -0.1778)
							(mid -0.249642 -0.249642)
							(end -0.1778 -0.2794)
						)
						(arc
							(start 0.1778 -0.2794)
							(mid 0.249642 -0.249642)
							(end 0.2794 -0.1778)
						)
						(arc
							(start 0.2794 0.1778)
							(mid 0.249642 0.249642)
							(end 0.1778 0.2794)
						)
					)
					(width 0)
					(fill yes)
				)
			)
		)
	)
	(footprint ""
		(layer "B.Cu")
		(at 128.2827 0.3302 180)
		(property "Reference" "R23"
			(at 0 0 0)
			(layer "B.SilkS")
			(hide yes)
			(effects
				(font
					(size 1.27 1.27)
				)
				(justify mirror)
			)
		)
		(property "Value" "4K7R2F-GP"
			(at -0.064008 -3.993896 180)
			(unlocked yes)
			(layer "B.Fab")
			(hide yes)
			(effects
				(font
					(size 1.016 1.016)
					(thickness 0.1524)
				)
				(justify mirror)
			)
		)
		(property "Device Type" "R402H16"
			(at -0.064008 -5.517896 180)
			(unlocked yes)
			(layer "B.Fab")
			(hide yes)
			(effects
				(font
					(size 1.016 1.016)
					(thickness 0.1524)
				)
				(justify mirror)
			)
		)
		(duplicate_pad_numbers_are_jumpers no)
		(fp_line
			(start 0.508 -0.9398)
			(end 0.508 0.9398)
			(stroke
				(width 0.1524)
				(type default)
			)
			(layer "B.SilkS")
		)
		(fp_line
			(start -0.508 -0.9398)
			(end 0.508 -0.9398)
			(stroke
				(width 0.1524)
				(type default)
			)
			(layer "B.SilkS")
		)
		(fp_rect
			(start 0.508 0.9398)
			(end -0.508 -0.9398)
			(stroke
				(width 0)
				(type default)
			)
			(fill no)
			(layer "B.CrtYd")
		)
		(fp_rect
			(start 0.508 0.9398)
			(end -0.508 -0.9398)
			(stroke
				(width 0)
				(type default)
			)
			(fill no)
			(layer "B.Fab")
		)
		(pad "1" smd custom
			(at 0 -0.4445)
			(size 0.1397 0.1397)
			(layers "B.Cu" "B.Mask" "B.Paste")
			(net "P3V3_STBY")
			(options
				(clearance outline)
				(anchor circle)
			)
			(primitives
				(gr_poly
					(pts
						(arc
							(start -0.1778 0.2794)
							(mid -0.249642 0.249642)
							(end -0.2794 0.1778)
						)
						(arc
							(start -0.2794 -0.1778)
							(mid -0.249642 -0.249642)
							(end -0.1778 -0.2794)
						)
						(arc
							(start 0.1778 -0.2794)
							(mid 0.249642 -0.249642)
							(end 0.2794 -0.1778)
						)
						(arc
							(start 0.2794 0.1778)
							(mid 0.249642 0.249642)
							(end 0.1778 0.2794)
						)
					)
					(width 0)
					(fill yes)
				)
			)
		)
		(pad "2" smd custom
			(at 0 0.4445)
			(size 0.1397 0.1397)
			(layers "B.Cu" "B.Mask" "B.Paste")
			(net "PU_P_MUX_SCL2")
			(options
				(clearance outline)
				(anchor circle)
			)
			(primitives
				(gr_poly
					(pts
						(arc
							(start -0.1778 0.2794)
							(mid -0.249642 0.249642)
							(end -0.2794 0.1778)
						)
						(arc
							(start -0.2794 -0.1778)
							(mid -0.249642 -0.249642)
							(end -0.1778 -0.2794)
						)
						(arc
							(start 0.1778 -0.2794)
							(mid 0.249642 -0.249642)
							(end 0.2794 -0.1778)
						)
						(arc
							(start 0.2794 0.1778)
							(mid 0.249642 0.249642)
							(end 0.1778 0.2794)
						)
					)
					(width 0)
					(fill yes)
				)
			)
		)
	)
)
